(kicad_pcb
	(version 20260206)
	(generator "pcbnew")
	(generator_version "10.0")
	(general
		(thickness 1.6)
		(legacy_teardrops no)
	)
	(paper "A4")
	(title_block
		(title "12092022_DA0F0TMDCD0_F0T_Management_Board_D_brd_V3_OCP.brd")
		(comment 1 "Grand Teton / footprints 1392-1397 of 1440")
	)
	(layers
		(0 "F.Cu" signal "TOP")
		(4 "In1.Cu" signal "GND")
		(6 "In2.Cu" signal "IN1")
		(8 "In3.Cu" signal "GND1")
		(10 "In4.Cu" signal "IN2")
		(12 "In5.Cu" signal "VCC")
		(14 "In6.Cu" signal "VCC1")
		(16 "In7.Cu" signal "IN3")
		(18 "In8.Cu" signal "GND2")
		(20 "In9.Cu" signal "IN4")
		(22 "In10.Cu" signal "GND3")
		(2 "B.Cu" signal "BOTTOM")
		(9 "F.Adhes" user "F.Adhesive")
		(11 "B.Adhes" user "B.Adhesive")
		(13 "F.Paste" user "Package Geometry/Pastemask Top")
		(15 "B.Paste" user "Package Geometry/Pastemask Bottom")
		(5 "F.SilkS" user "Ref Des/Silkscreen Top")
		(7 "B.SilkS" user "Ref Des/Silkscreen Bottom")
		(1 "F.Mask" user "Board Geometry/Soldermask Top")
		(3 "B.Mask" user "Board Geometry/Soldermask Bottom")
		(17 "Dwgs.User" user "User.Drawings")
		(19 "Cmts.User" user "User.Comments")
		(21 "Eco1.User" user "User.Eco1")
		(23 "Eco2.User" user "User.Eco2")
		(25 "Edge.Cuts" user "Board Geometry/Outline")
		(27 "Margin" user)
		(31 "F.CrtYd" user "Package Geometry/Place Bound Top")
		(29 "B.CrtYd" user "Package Geometry/Place Bound Bottom")
		(35 "F.Fab" user "Ref Des/Assembly Top")
		(33 "B.Fab" user "Ref Des/Assembly Bottom")
	)
	(footprint ""
		(layer "B.Cu")
		(at 12.32662 -56.00192 180)
		(property "Reference" "R292"
			(at 0 0 0)
			(layer "B.SilkS")
			(hide yes)
			(effects
				(font
					(size 1.27 1.27)
				)
				(justify mirror)
			)
		)
		(property "Value" ""
			(at 0 0 0)
			(layer "B.Fab")
			(effects
				(font
					(size 1.27 1.27)
				)
				(justify mirror)
			)
		)
		(duplicate_pad_numbers_are_jumpers no)
		(fp_line
			(start 0.7874 0.4064)
			(end 0.7874 -0.4064)
			(stroke
				(width 0.1524)
				(type default)
			)
			(layer "B.SilkS")
		)
		(fp_line
			(start 0.7874 -0.4064)
			(end -0.7874 -0.4064)
			(stroke
				(width 0.1524)
				(type default)
			)
			(layer "B.SilkS")
		)
		(fp_line
			(start -0.7874 0.4064)
			(end 0.7874 0.4064)
			(stroke
				(width 0.1524)
				(type default)
			)
			(layer "B.SilkS")
		)
		(fp_line
			(start -0.7874 -0.4064)
			(end -0.7874 0.4064)
			(stroke
				(width 0.1524)
				(type default)
			)
			(layer "B.SilkS")
		)
		(fp_line
			(start 0.67945 0.3048)
			(end 0.67945 -0.305054)
			(stroke
				(width 0.1)
				(type default)
			)
			(layer "B.Fab")
		)
		(fp_line
			(start 0.67945 -0.305054)
			(end 0.12065 -0.305054)
			(stroke
				(width 0.1)
				(type default)
			)
			(layer "B.Fab")
		)
		(fp_line
			(start 0.12065 0.3048)
			(end 0.67945 0.3048)
			(stroke
				(width 0.1)
				(type default)
			)
			(layer "B.Fab")
		)
		(fp_line
			(start 0.12065 0.2794)
			(end 0.12065 0.3048)
			(stroke
				(width 0.1)
				(type default)
			)
			(layer "B.Fab")
		)
		(fp_line
			(start 0.12065 -0.2794)
			(end -0.12065 -0.2794)
			(stroke
				(width 0.1)
				(type default)
			)
			(layer "B.Fab")
		)
		(fp_line
			(start 0.12065 -0.305054)
			(end 0.12065 -0.2794)
			(stroke
				(width 0.1)
				(type default)
			)
			(layer "B.Fab")
		)
		(fp_line
			(start -0.120396 0.3048)
			(end -0.120396 0.2794)
			(stroke
				(width 0.1)
				(type default)
			)
			(layer "B.Fab")
		)
		(fp_line
			(start -0.120396 0.2794)
			(end 0.12065 0.2794)
			(stroke
				(width 0.1)
				(type default)
			)
			(layer "B.Fab")
		)
		(fp_line
			(start -0.12065 -0.2794)
			(end -0.12065 -0.3048)
			(stroke
				(width 0.1)
				(type default)
			)
			(layer "B.Fab")
		)
		(fp_line
			(start -0.12065 -0.3048)
			(end -0.67945 -0.3048)
			(stroke
				(width 0.1)
				(type default)
			)
			(layer "B.Fab")
		)
		(fp_line
			(start -0.67945 0.3048)
			(end -0.120396 0.3048)
			(stroke
				(width 0.1)
				(type default)
			)
			(layer "B.Fab")
		)
		(fp_line
			(start -0.67945 -0.3048)
			(end -0.67945 0.3048)
			(stroke
				(width 0.1)
				(type default)
			)
			(layer "B.Fab")
		)
		(pad "1" smd circle
			(at 0.40005 0)
			(size 0 0)
			(layers "B.Cu" "B.Mask" "B.Paste")
			(net "PWRGD_P5V_AUX_R")
		)
		(pad "2" smd circle
			(at -0.40005 0)
			(size 0 0)
			(layers "B.Cu" "B.Mask" "B.Paste")
			(net "PWRGD_P5V_AUX")
		)
	)
	(footprint ""
		(layer "B.Cu")
		(at 32.004 -101.854 90)
		(property "Reference" "R450"
			(at 0 0 90)
			(layer "B.SilkS")
			(hide yes)
			(effects
				(font
					(size 1.27 1.27)
				)
				(justify mirror)
			)
		)
		(property "Value" ""
			(at 0 0 90)
			(layer "B.Fab")
			(effects
				(font
					(size 1.27 1.27)
				)
				(justify mirror)
			)
		)
		(duplicate_pad_numbers_are_jumpers no)
		(fp_line
			(start 0.7874 -0.4064)
			(end -0.7874 -0.4064)
			(stroke
				(width 0.1524)
				(type default)
			)
			(layer "B.SilkS")
		)
		(fp_line
			(start -0.7874 -0.4064)
			(end -0.7874 0.4064)
			(stroke
				(width 0.1524)
				(type default)
			)
			(layer "B.SilkS")
		)
		(fp_line
			(start 0.7874 0.4064)
			(end 0.7874 -0.4064)
			(stroke
				(width 0.1524)
				(type default)
			)
			(layer "B.SilkS")
		)
		(fp_line
			(start -0.7874 0.4064)
			(end 0.7874 0.4064)
			(stroke
				(width 0.1524)
				(type default)
			)
			(layer "B.SilkS")
		)
		(fp_line
			(start 0.67945 -0.305054)
			(end 0.12065 -0.305054)
			(stroke
				(width 0.1)
				(type default)
			)
			(layer "B.Fab")
		)
		(fp_line
			(start 0.12065 -0.305054)
			(end 0.12065 -0.2794)
			(stroke
				(width 0.1)
				(type default)
			)
			(layer "B.Fab")
		)
		(fp_line
			(start -0.12065 -0.3048)
			(end -0.67945 -0.3048)
			(stroke
				(width 0.1)
				(type default)
			)
			(layer "B.Fab")
		)
		(fp_line
			(start -0.67945 -0.3048)
			(end -0.67945 0.3048)
			(stroke
				(width 0.1)
				(type default)
			)
			(layer "B.Fab")
		)
		(fp_line
			(start 0.12065 -0.2794)
			(end -0.12065 -0.2794)
			(stroke
				(width 0.1)
				(type default)
			)
			(layer "B.Fab")
		)
		(fp_line
			(start -0.12065 -0.2794)
			(end -0.12065 -0.3048)
			(stroke
				(width 0.1)
				(type default)
			)
			(layer "B.Fab")
		)
		(fp_line
			(start 0.12065 0.2794)
			(end 0.12065 0.3048)
			(stroke
				(width 0.1)
				(type default)
			)
			(layer "B.Fab")
		)
		(fp_line
			(start -0.120396 0.2794)
			(end 0.12065 0.2794)
			(stroke
				(width 0.1)
				(type default)
			)
			(layer "B.Fab")
		)
		(fp_line
			(start 0.67945 0.3048)
			(end 0.67945 -0.305054)
			(stroke
				(width 0.1)
				(type default)
			)
			(layer "B.Fab")
		)
		(fp_line
			(start 0.12065 0.3048)
			(end 0.67945 0.3048)
			(stroke
				(width 0.1)
				(type default)
			)
			(layer "B.Fab")
		)
		(fp_line
			(start -0.120396 0.3048)
			(end -0.120396 0.2794)
			(stroke
				(width 0.1)
				(type default)
			)
			(layer "B.Fab")
		)
		(fp_line
			(start -0.67945 0.3048)
			(end -0.120396 0.3048)
			(stroke
				(width 0.1)
				(type default)
			)
			(layer "B.Fab")
		)
		(pad "1" smd circle
			(at 0.40005 0 270)
			(size 0 0)
			(layers "B.Cu" "B.Mask" "B.Paste")
			(net "RST_BMC_SELF_HW")
		)
		(pad "2" smd circle
			(at -0.40005 0 270)
			(size 0 0)
			(layers "B.Cu" "B.Mask" "B.Paste")
			(net "RST_BMC_SELF_HW_R3")
		)
	)
	(footprint ""
		(layer "B.Cu")
		(at 75.5396 -29.5402 180)
		(property "Reference" "R697"
			(at 0 0 0)
			(layer "B.SilkS")
			(hide yes)
			(effects
				(font
					(size 1.27 1.27)
				)
				(justify mirror)
			)
		)
		(property "Value" ""
			(at 0 0 0)
			(layer "B.Fab")
			(effects
				(font
					(size 1.27 1.27)
				)
				(justify mirror)
			)
		)
		(duplicate_pad_numbers_are_jumpers no)
		(fp_line
			(start 0.7874 0.4064)
			(end 0.7874 -0.4064)
			(stroke
				(width 0.1524)
				(type default)
			)
			(layer "B.SilkS")
		)
		(fp_line
			(start 0.7874 -0.4064)
			(end -0.7874 -0.4064)
			(stroke
				(width 0.1524)
				(type default)
			)
			(layer "B.SilkS")
		)
		(fp_line
			(start -0.7874 0.4064)
			(end 0.7874 0.4064)
			(stroke
				(width 0.1524)
				(type default)
			)
			(layer "B.SilkS")
		)
		(fp_line
			(start -0.7874 -0.4064)
			(end -0.7874 0.4064)
			(stroke
				(width 0.1524)
				(type default)
			)
			(layer "B.SilkS")
		)
		(fp_line
			(start 0.67945 0.3048)
			(end 0.67945 -0.305054)
			(stroke
				(width 0.1)
				(type default)
			)
			(layer "B.Fab")
		)
		(fp_line
			(start 0.67945 -0.305054)
			(end 0.12065 -0.305054)
			(stroke
				(width 0.1)
				(type default)
			)
			(layer "B.Fab")
		)
		(fp_line
			(start 0.12065 0.3048)
			(end 0.67945 0.3048)
			(stroke
				(width 0.1)
				(type default)
			)
			(layer "B.Fab")
		)
		(fp_line
			(start 0.12065 0.2794)
			(end 0.12065 0.3048)
			(stroke
				(width 0.1)
				(type default)
			)
			(layer "B.Fab")
		)
		(fp_line
			(start 0.12065 -0.2794)
			(end -0.12065 -0.2794)
			(stroke
				(width 0.1)
				(type default)
			)
			(layer "B.Fab")
		)
		(fp_line
			(start 0.12065 -0.305054)
			(end 0.12065 -0.2794)
			(stroke
				(width 0.1)
				(type default)
			)
			(layer "B.Fab")
		)
		(fp_line
			(start -0.120396 0.3048)
			(end -0.120396 0.2794)
			(stroke
				(width 0.1)
				(type default)
			)
			(layer "B.Fab")
		)
		(fp_line
			(start -0.120396 0.2794)
			(end 0.12065 0.2794)
			(stroke
				(width 0.1)
				(type default)
			)
			(layer "B.Fab")
		)
		(fp_line
			(start -0.12065 -0.2794)
			(end -0.12065 -0.3048)
			(stroke
				(width 0.1)
				(type default)
			)
			(layer "B.Fab")
		)
		(fp_line
			(start -0.12065 -0.3048)
			(end -0.67945 -0.3048)
			(stroke
				(width 0.1)
				(type default)
			)
			(layer "B.Fab")
		)
		(fp_line
			(start -0.67945 0.3048)
			(end -0.120396 0.3048)
			(stroke
				(width 0.1)
				(type default)
			)
			(layer "B.Fab")
		)
		(fp_line
			(start -0.67945 -0.3048)
			(end -0.67945 0.3048)
			(stroke
				(width 0.1)
				(type default)
			)
			(layer "B.Fab")
		)
		(pad "1" smd circle
			(at 0.40005 0)
			(size 0 0)
			(layers "B.Cu" "B.Mask" "B.Paste")
			(net "LED_POSTCODE_2")
		)
		(pad "2" smd circle
			(at -0.40005 0)
			(size 0 0)
			(layers "B.Cu" "B.Mask" "B.Paste")
			(net "LED_POSTCODE_2_R1")
		)
	)
	(footprint ""
		(layer "B.Cu")
		(at 38.1 -106.3625 -90)
		(property "Reference" "R227"
			(at 0 0 90)
			(layer "B.SilkS")
			(hide yes)
			(effects
				(font
					(size 1.27 1.27)
				)
				(justify mirror)
			)
		)
		(property "Value" ""
			(at 0 0 90)
			(layer "B.Fab")
			(effects
				(font
					(size 1.27 1.27)
				)
				(justify mirror)
			)
		)
		(duplicate_pad_numbers_are_jumpers no)
		(fp_line
			(start -0.7874 0.4064)
			(end 0.7874 0.4064)
			(stroke
				(width 0.1524)
				(type default)
			)
			(layer "B.SilkS")
		)
		(fp_line
			(start 0.7874 0.4064)
			(end 0.7874 -0.4064)
			(stroke
				(width 0.1524)
				(type default)
			)
			(layer "B.SilkS")
		)
		(fp_line
			(start -0.7874 -0.4064)
			(end -0.7874 0.4064)
			(stroke
				(width 0.1524)
				(type default)
			)
			(layer "B.SilkS")
		)
		(fp_line
			(start 0.7874 -0.4064)
			(end -0.7874 -0.4064)
			(stroke
				(width 0.1524)
				(type default)
			)
			(layer "B.SilkS")
		)
		(fp_line
			(start -0.67945 0.3048)
			(end -0.120396 0.3048)
			(stroke
				(width 0.1)
				(type default)
			)
			(layer "B.Fab")
		)
		(fp_line
			(start -0.120396 0.3048)
			(end -0.120396 0.2794)
			(stroke
				(width 0.1)
				(type default)
			)
			(layer "B.Fab")
		)
		(fp_line
			(start 0.12065 0.3048)
			(end 0.67945 0.3048)
			(stroke
				(width 0.1)
				(type default)
			)
			(layer "B.Fab")
		)
		(fp_line
			(start 0.67945 0.3048)
			(end 0.67945 -0.305054)
			(stroke
				(width 0.1)
				(type default)
			)
			(layer "B.Fab")
		)
		(fp_line
			(start -0.120396 0.2794)
			(end 0.12065 0.2794)
			(stroke
				(width 0.1)
				(type default)
			)
			(layer "B.Fab")
		)
		(fp_line
			(start 0.12065 0.2794)
			(end 0.12065 0.3048)
			(stroke
				(width 0.1)
				(type default)
			)
			(layer "B.Fab")
		)
		(fp_line
			(start -0.12065 -0.2794)
			(end -0.12065 -0.3048)
			(stroke
				(width 0.1)
				(type default)
			)
			(layer "B.Fab")
		)
		(fp_line
			(start 0.12065 -0.2794)
			(end -0.12065 -0.2794)
			(stroke
				(width 0.1)
				(type default)
			)
			(layer "B.Fab")
		)
		(fp_line
			(start -0.67945 -0.3048)
			(end -0.67945 0.3048)
			(stroke
				(width 0.1)
				(type default)
			)
			(layer "B.Fab")
		)
		(fp_line
			(start -0.12065 -0.3048)
			(end -0.67945 -0.3048)
			(stroke
				(width 0.1)
				(type default)
			)
			(layer "B.Fab")
		)
		(fp_line
			(start 0.12065 -0.305054)
			(end 0.12065 -0.2794)
			(stroke
				(width 0.1)
				(type default)
			)
			(layer "B.Fab")
		)
		(fp_line
			(start 0.67945 -0.305054)
			(end 0.12065 -0.305054)
			(stroke
				(width 0.1)
				(type default)
			)
			(layer "B.Fab")
		)
		(pad "1" smd circle
			(at 0.40005 0 90)
			(size 0 0)
			(layers "B.Cu" "B.Mask" "B.Paste")
			(net "P3V3_AUX")
		)
		(pad "2" smd circle
			(at -0.40005 0 90)
			(size 0 0)
			(layers "B.Cu" "B.Mask" "B.Paste")
			(net "JTAG_MB_TMS")
		)
	)
	(footprint ""
		(layer "B.Cu")
		(at 32.766 -90.805 180)
		(property "Reference" "C256"
			(at 0 0 0)
			(layer "B.SilkS")
			(hide yes)
			(effects
				(font
					(size 1.27 1.27)
				)
				(justify mirror)
			)
		)
		(property "Value" ""
			(at 0 0 0)
			(layer "B.Fab")
			(effects
				(font
					(size 1.27 1.27)
				)
				(justify mirror)
			)
		)
		(duplicate_pad_numbers_are_jumpers no)
		(fp_line
			(start 0.7874 0.4064)
			(end 0.7874 -0.4064)
			(stroke
				(width 0.1524)
				(type default)
			)
			(layer "B.SilkS")
		)
		(fp_line
			(start 0.7874 -0.4064)
			(end -0.7874 -0.4064)
			(stroke
				(width 0.1524)
				(type default)
			)
			(layer "B.SilkS")
		)
		(fp_line
			(start -0.7874 0.4064)
			(end 0.7874 0.4064)
			(stroke
				(width 0.1524)
				(type default)
			)
			(layer "B.SilkS")
		)
		(fp_line
			(start -0.7874 -0.4064)
			(end -0.7874 0.4064)
			(stroke
				(width 0.1524)
				(type default)
			)
			(layer "B.SilkS")
		)
		(fp_line
			(start 0.67945 0.3048)
			(end 0.67945 -0.305054)
			(stroke
				(width 0.1)
				(type default)
			)
			(layer "B.Fab")
		)
		(fp_line
			(start 0.67945 -0.305054)
			(end 0.12065 -0.305054)
			(stroke
				(width 0.1)
				(type default)
			)
			(layer "B.Fab")
		)
		(fp_line
			(start 0.12065 0.3048)
			(end 0.67945 0.3048)
			(stroke
				(width 0.1)
				(type default)
			)
			(layer "B.Fab")
		)
		(fp_line
			(start 0.12065 0.2794)
			(end 0.12065 0.3048)
			(stroke
				(width 0.1)
				(type default)
			)
			(layer "B.Fab")
		)
		(fp_line
			(start 0.12065 -0.2794)
			(end -0.12065 -0.2794)
			(stroke
				(width 0.1)
				(type default)
			)
			(layer "B.Fab")
		)
		(fp_line
			(start 0.12065 -0.305054)
			(end 0.12065 -0.2794)
			(stroke
				(width 0.1)
				(type default)
			)
			(layer "B.Fab")
		)
		(fp_line
			(start -0.120396 0.3048)
			(end -0.120396 0.2794)
			(stroke
				(width 0.1)
				(type default)
			)
			(layer "B.Fab")
		)
		(fp_line
			(start -0.120396 0.2794)
			(end 0.12065 0.2794)
			(stroke
				(width 0.1)
				(type default)
			)
			(layer "B.Fab")
		)
		(fp_line
			(start -0.12065 -0.2794)
			(end -0.12065 -0.3048)
			(stroke
				(width 0.1)
				(type default)
			)
			(layer "B.Fab")
		)
		(fp_line
			(start -0.12065 -0.3048)
			(end -0.67945 -0.3048)
			(stroke
				(width 0.1)
				(type default)
			)
			(layer "B.Fab")
		)
		(fp_line
			(start -0.67945 0.3048)
			(end -0.120396 0.3048)
			(stroke
				(width 0.1)
				(type default)
			)
			(layer "B.Fab")
		)
		(fp_line
			(start -0.67945 -0.3048)
			(end -0.67945 0.3048)
			(stroke
				(width 0.1)
				(type default)
			)
			(layer "B.Fab")
		)
		(pad "1" smd circle
			(at 0.40005 0)
			(size 0 0)
			(layers "B.Cu" "B.Mask" "B.Paste")
			(net "PVCCIO_AUX_PLD")
		)
		(pad "2" smd circle
			(at -0.40005 0)
			(size 0 0)
			(layers "B.Cu" "B.Mask" "B.Paste")
			(net "GND")
		)
	)
	(footprint ""
		(layer "B.Cu")
		(at 19.05 -98.679 90)
		(property "Reference" "R304"
			(at 0 0 90)
			(layer "B.SilkS")
			(hide yes)
			(effects
				(font
					(size 1.27 1.27)
				)
				(justify mirror)
			)
		)
		(property "Value" ""
			(at 0 0 90)
			(layer "B.Fab")
			(effects
				(font
					(size 1.27 1.27)
				)
				(justify mirror)
			)
		)
		(duplicate_pad_numbers_are_jumpers no)
		(fp_line
			(start 0.7874 -0.4064)
			(end -0.7874 -0.4064)
			(stroke
				(width 0.1524)
				(type default)
			)
			(layer "B.SilkS")
		)
		(fp_line
			(start -0.7874 -0.4064)
			(end -0.7874 0.4064)
			(stroke
				(width 0.1524)
				(type default)
			)
			(layer "B.SilkS")
		)
		(fp_line
			(start 0.7874 0.4064)
			(end 0.7874 -0.4064)
			(stroke
				(width 0.1524)
				(type default)
			)
			(layer "B.SilkS")
		)
		(fp_line
			(start -0.7874 0.4064)
			(end 0.7874 0.4064)
			(stroke
				(width 0.1524)
				(type default)
			)
			(layer "B.SilkS")
		)
		(fp_line
			(start 0.67945 -0.305054)
			(end 0.12065 -0.305054)
			(stroke
				(width 0.1)
				(type default)
			)
			(layer "B.Fab")
		)
		(fp_line
			(start 0.12065 -0.305054)
			(end 0.12065 -0.2794)
			(stroke
				(width 0.1)
				(type default)
			)
			(layer "B.Fab")
		)
		(fp_line
			(start -0.12065 -0.3048)
			(end -0.67945 -0.3048)
			(stroke
				(width 0.1)
				(type default)
			)
			(layer "B.Fab")
		)
		(fp_line
			(start -0.67945 -0.3048)
			(end -0.67945 0.3048)
			(stroke
				(width 0.1)
				(type default)
			)
			(layer "B.Fab")
		)
		(fp_line
			(start 0.12065 -0.2794)
			(end -0.12065 -0.2794)
			(stroke
				(width 0.1)
				(type default)
			)
			(layer "B.Fab")
		)
		(fp_line
			(start -0.12065 -0.2794)
			(end -0.12065 -0.3048)
			(stroke
				(width 0.1)
				(type default)
			)
			(layer "B.Fab")
		)
		(fp_line
			(start 0.12065 0.2794)
			(end 0.12065 0.3048)
			(stroke
				(width 0.1)
				(type default)
			)
			(layer "B.Fab")
		)
		(fp_line
			(start -0.120396 0.2794)
			(end 0.12065 0.2794)
			(stroke
				(width 0.1)
				(type default)
			)
			(layer "B.Fab")
		)
		(fp_line
			(start 0.67945 0.3048)
			(end 0.67945 -0.305054)
			(stroke
				(width 0.1)
				(type default)
			)
			(layer "B.Fab")
		)
		(fp_line
			(start 0.12065 0.3048)
			(end 0.67945 0.3048)
			(stroke
				(width 0.1)
				(type default)
			)
			(layer "B.Fab")
		)
		(fp_line
			(start -0.120396 0.3048)
			(end -0.120396 0.2794)
			(stroke
				(width 0.1)
				(type default)
			)
			(layer "B.Fab")
		)
		(fp_line
			(start -0.67945 0.3048)
			(end -0.120396 0.3048)
			(stroke
				(width 0.1)
				(type default)
			)
			(layer "B.Fab")
		)
		(pad "1" smd circle
			(at 0.40005 0 270)
			(size 0 0)
			(layers "B.Cu" "B.Mask" "B.Paste")
			(net "P3V3_AUX")
		)
		(pad "2" smd circle
			(at -0.40005 0 270)
			(size 0 0)
			(layers "B.Cu" "B.Mask" "B.Paste")
			(net "VCCIO2")
		)
	)
)
